# T6G (Grand Teton) — schematic netlist excerpt (pin names and nets, part order shuffled) for the footprints in the layout excerpt that follows; sources: Cadence DE-HDL packaged netlist, KiCad conversion of 04192023_DAF0TMB3IC0_F0TG_MB_C_brd_V02_OCP.brd

R8087  Q_RES  0 5% CHIP  pkg 0402LF  page 98 : A = PWRGD_CHAF_CPU1_R1 ; B = PWRGD_CHAF_CPU1_R2
PC568  Q_CAP  0.22UF 25V 10% X7R  pkg C0402  page 190 : A = SW_P3V3_AUX_BOOTR ; B = SW_P3V3_AUX_BOOT_R

(kicad_pcb
	(version 20260206)
	(generator "pcbnew")
	(generator_version "10.0")
	(general
		(thickness 1.6)
		(legacy_teardrops no)
	)
	(paper "A4")
	(title_block
		(title "04192023_DAF0TMB3IC0_F0TG_MB_C_brd_V02_OCP.brd")
		(comment 1 "Grand Teton / footprints 3966-3967 of 8354")
	)
	(layers
		(0 "F.Cu" signal "TOP")
		(4 "In1.Cu" signal "GND")
		(6 "In2.Cu" signal "IN1")
		(8 "In3.Cu" signal "GND1")
		(10 "In4.Cu" signal "IN2")
		(12 "In5.Cu" signal "GND2")
		(14 "In6.Cu" signal "IN3")
		(16 "In7.Cu" signal "GND3")
		(18 "In8.Cu" signal "VCC")
		(20 "In9.Cu" signal "VCC1")
		(22 "In10.Cu" signal "GND4")
		(24 "In11.Cu" signal "IN4")
		(26 "In12.Cu" signal "GND5")
		(28 "In13.Cu" signal "IN5")
		(30 "In14.Cu" signal "GND6")
		(32 "In15.Cu" signal "IN6")
		(34 "In16.Cu" signal "GND7")
		(2 "B.Cu" signal "BOTTOM")
		(9 "F.Adhes" user "F.Adhesive")
		(11 "B.Adhes" user "B.Adhesive")
		(13 "F.Paste" user "Package Geometry/Pastemask Top")
		(15 "B.Paste" user "Package Geometry/Pastemask Bottom")
		(5 "F.SilkS" user "Ref Des/Silkscreen Top")
		(7 "B.SilkS" user "Ref Des/Silkscreen Bottom")
		(1 "F.Mask" user "Board Geometry/Soldermask Top")
		(3 "B.Mask" user "Board Geometry/Soldermask Bottom")
		(17 "Dwgs.User" user "User.Drawings")
		(19 "Cmts.User" user "User.Comments")
		(21 "Eco1.User" user "User.Eco1")
		(23 "Eco2.User" user "User.Eco2")
		(25 "Edge.Cuts" user "Board Geometry/Outline")
		(27 "Margin" user)
		(31 "F.CrtYd" user "Package Geometry/Place Bound Top")
		(29 "B.CrtYd" user "Package Geometry/Place Bound Bottom")
		(35 "F.Fab" user "Ref Des/Assembly Top")
		(33 "B.Fab" user "Ref Des/Assembly Bottom")
	)
	(footprint ""
		(layer "F.Cu")
		(at 452.153274 -50.266346 180)
		(property "Reference" "PC568"
			(at 0 0 180)
			(layer "F.SilkS")
			(hide yes)
			(effects
				(font
					(size 1.27 1.27)
				)
			)
		)
		(property "Value" ""
			(at 0 0 180)
			(layer "F.Fab")
			(effects
				(font
					(size 1.27 1.27)
				)
			)
		)
		(duplicate_pad_numbers_are_jumpers no)
		(fp_line
			(start 0.7874 0.4064)
			(end -0.7874 0.4064)
			(stroke
				(width 0.1524)
				(type default)
			)
			(layer "F.SilkS")
		)
		(fp_line
			(start 0.7874 -0.4064)
			(end 0.7874 0.4064)
			(stroke
				(width 0.1524)
				(type default)
			)
			(layer "F.SilkS")
		)
		(fp_line
			(start -0.7874 0.4064)
			(end -0.7874 -0.4064)
			(stroke
				(width 0.1524)
				(type default)
			)
			(layer "F.SilkS")
		)
		(fp_line
			(start -0.7874 -0.4064)
			(end 0.7874 -0.4064)
			(stroke
				(width 0.1524)
				(type default)
			)
			(layer "F.SilkS")
		)
		(fp_line
			(start 0.67945 0.3048)
			(end 0.120396 0.3048)
			(stroke
				(width 0.1)
				(type default)
			)
			(layer "F.Fab")
		)
		(fp_line
			(start 0.67945 -0.3048)
			(end 0.67945 0.3048)
			(stroke
				(width 0.1)
				(type default)
			)
			(layer "F.Fab")
		)
		(fp_line
			(start 0.12065 -0.2794)
			(end 0.12065 -0.3048)
			(stroke
				(width 0.1)
				(type default)
			)
			(layer "F.Fab")
		)
		(fp_line
			(start 0.12065 -0.3048)
			(end 0.67945 -0.3048)
			(stroke
				(width 0.1)
				(type default)
			)
			(layer "F.Fab")
		)
		(fp_line
			(start 0.120396 0.3048)
			(end 0.120396 0.2794)
			(stroke
				(width 0.1)
				(type default)
			)
			(layer "F.Fab")
		)
		(fp_line
			(start 0.120396 0.2794)
			(end -0.12065 0.2794)
			(stroke
				(width 0.1)
				(type default)
			)
			(layer "F.Fab")
		)
		(fp_line
			(start -0.12065 0.3048)
			(end -0.67945 0.3048)
			(stroke
				(width 0.1)
				(type default)
			)
			(layer "F.Fab")
		)
		(fp_line
			(start -0.12065 0.2794)
			(end -0.12065 0.3048)
			(stroke
				(width 0.1)
				(type default)
			)
			(layer "F.Fab")
		)
		(fp_line
			(start -0.12065 -0.2794)
			(end 0.12065 -0.2794)
			(stroke
				(width 0.1)
				(type default)
			)
			(layer "F.Fab")
		)
		(fp_line
			(start -0.12065 -0.305054)
			(end -0.12065 -0.2794)
			(stroke
				(width 0.1)
				(type default)
			)
			(layer "F.Fab")
		)
		(fp_line
			(start -0.67945 0.3048)
			(end -0.67945 -0.305054)
			(stroke
				(width 0.1)
				(type default)
			)
			(layer "F.Fab")
		)
		(fp_line
			(start -0.67945 -0.305054)
			(end -0.12065 -0.305054)
			(stroke
				(width 0.1)
				(type default)
			)
			(layer "F.Fab")
		)
		(pad "1" smd circle
			(at -0.40005 0 180)
			(size 0 0)
			(layers "F.Cu" "F.Mask" "F.Paste")
			(net "SW_P3V3_AUX_BOOTR")
		)
		(pad "2" smd circle
			(at 0.40005 0 180)
			(size 0 0)
			(layers "F.Cu" "F.Mask" "F.Paste")
			(net "SW_P3V3_AUX_BOOT_R")
		)
	)
	(footprint ""
		(layer "F.Cu")
		(at 151.257 -125.349)
		(property "Reference" "R8087"
			(at 0 0 0)
			(layer "F.SilkS")
			(hide yes)
			(effects
				(font
					(size 1.27 1.27)
				)
			)
		)
		(property "Value" ""
			(at 0 0 0)
			(layer "F.Fab")
			(effects
				(font
					(size 1.27 1.27)
				)
			)
		)
		(duplicate_pad_numbers_are_jumpers no)
		(fp_line
			(start -0.7874 -0.4064)
			(end 0.7874 -0.4064)
			(stroke
				(width 0.1524)
				(type default)
			)
			(layer "F.SilkS")
		)
		(fp_line
			(start -0.7874 0.4064)
			(end -0.7874 -0.4064)
			(stroke
				(width 0.1524)
				(type default)
			)
			(layer "F.SilkS")
		)
		(fp_line
			(start 0.7874 -0.4064)
			(end 0.7874 0.4064)
			(stroke
				(width 0.1524)
				(type default)
			)
			(layer "F.SilkS")
		)
		(fp_line
			(start 0.7874 0.4064)
			(end -0.7874 0.4064)
			(stroke
				(width 0.1524)
				(type default)
			)
			(layer "F.SilkS")
		)
		(fp_line
			(start -0.67945 -0.305054)
			(end -0.12065 -0.305054)
			(stroke
				(width 0.1)
				(type default)
			)
			(layer "F.Fab")
		)
		(fp_line
			(start -0.67945 0.3048)
			(end -0.67945 -0.305054)
			(stroke
				(width 0.1)
				(type default)
			)
			(layer "F.Fab")
		)
		(fp_line
			(start -0.12065 -0.305054)
			(end -0.12065 -0.2794)
			(stroke
				(width 0.1)
				(type default)
			)
			(layer "F.Fab")
		)
		(fp_line
			(start -0.12065 -0.2794)
			(end 0.12065 -0.2794)
			(stroke
				(width 0.1)
				(type default)
			)
			(layer "F.Fab")
		)
		(fp_line
			(start -0.12065 0.2794)
			(end -0.12065 0.3048)
			(stroke
				(width 0.1)
				(type default)
			)
			(layer "F.Fab")
		)
		(fp_line
			(start -0.12065 0.3048)
			(end -0.67945 0.3048)
			(stroke
				(width 0.1)
				(type default)
			)
			(layer "F.Fab")
		)
		(fp_line
			(start 0.120396 0.2794)
			(end -0.12065 0.2794)
			(stroke
				(width 0.1)
				(type default)
			)
			(layer "F.Fab")
		)
		(fp_line
			(start 0.120396 0.3048)
			(end 0.120396 0.2794)
			(stroke
				(width 0.1)
				(type default)
			)
			(layer "F.Fab")
		)
		(fp_line
			(start 0.12065 -0.3048)
			(end 0.67945 -0.3048)
			(stroke
				(width 0.1)
				(type default)
			)
			(layer "F.Fab")
		)
		(fp_line
			(start 0.12065 -0.2794)
			(end 0.12065 -0.3048)
			(stroke
				(width 0.1)
				(type default)
			)
			(layer "F.Fab")
		)
		(fp_line
			(start 0.67945 -0.3048)
			(end 0.67945 0.3048)
			(stroke
				(width 0.1)
				(type default)
			)
			(layer "F.Fab")
		)
		(fp_line
			(start 0.67945 0.3048)
			(end 0.120396 0.3048)
			(stroke
				(width 0.1)
				(type default)
			)
			(layer "F.Fab")
		)
		(pad "1" smd circle
			(at -0.40005 0)
			(size 0 0)
			(layers "F.Cu" "F.Mask" "F.Paste")
			(net "PWRGD_CHAF_CPU1_R1")
		)
		(pad "2" smd circle
			(at 0.40005 0)
			(size 0 0)
			(layers "F.Cu" "F.Mask" "F.Paste")
			(net "PWRGD_CHAF_CPU1_R2")
		)
	)
)
